(kicad_pcb
	(version 20260206)
	(generator "pcbnew")
	(generator_version "10.0")
	(general
		(thickness 1.6)
		(legacy_teardrops no)
	)
	(paper "A4")
	(title_block
		(title "Wiwynn_Tioga_Pass_MB.brd")
		(comment 1 "Tioga Pass / footprints 3182-3188 of 4770")
	)
	(layers
		(0 "F.Cu" signal "TOP")
		(4 "In1.Cu" signal "L2GND")
		(6 "In2.Cu" signal "L3")
		(8 "In3.Cu" signal "L4GND")
		(10 "In4.Cu" signal "L5")
		(12 "In5.Cu" signal "L6GND")
		(14 "In6.Cu" signal "L7VCC")
		(16 "In7.Cu" signal "L8VCC")
		(18 "In8.Cu" signal "L9GND")
		(20 "In9.Cu" signal "L10")
		(22 "In10.Cu" signal "L11GND")
		(24 "In11.Cu" signal "L12")
		(26 "In12.Cu" signal "L13GND")
		(2 "B.Cu" signal "BOTTOM")
		(9 "F.Adhes" user "F.Adhesive")
		(11 "B.Adhes" user "B.Adhesive")
		(13 "F.Paste" user "Package Geometry/Pastemask Top")
		(15 "B.Paste" user "Package Geometry/Pastemask Bottom")
		(5 "F.SilkS" user "Ref Des/Silkscreen Top")
		(7 "B.SilkS" user "Ref Des/Silkscreen Bottom")
		(1 "F.Mask" user "Board Geometry/Soldermask Top")
		(3 "B.Mask" user "Board Geometry/Soldermask Bottom")
		(17 "Dwgs.User" user "User.Drawings")
		(19 "Cmts.User" user "User.Comments")
		(21 "Eco1.User" user "User.Eco1")
		(23 "Eco2.User" user "User.Eco2")
		(25 "Edge.Cuts" user "Board Geometry/Outline")
		(27 "Margin" user)
		(31 "F.CrtYd" user "Package Geometry/Place Bound Top")
		(29 "B.CrtYd" user "Package Geometry/Place Bound Bottom")
		(35 "F.Fab" user "Ref Des/Assembly Top")
		(33 "B.Fab" user "Ref Des/Assembly Bottom")
	)
	(footprint ""
		(layer "B.Cu")
		(at 387.5786 -114.9096 90)
		(property "Reference" "C3M38"
			(at 0 0 90)
			(layer "B.SilkS")
			(hide yes)
			(effects
				(font
					(size 1.27 1.27)
				)
				(justify mirror)
			)
		)
		(property "Value" ""
			(at 0 0 90)
			(layer "B.Fab")
			(effects
				(font
					(size 1.27 1.27)
				)
				(justify mirror)
			)
		)
		(duplicate_pad_numbers_are_jumpers no)
		(fp_rect
			(start 0.2794 0.9144)
			(end -0.2794 -0.1143)
			(stroke
				(width 0)
				(type default)
			)
			(fill no)
			(layer "B.CrtYd")
		)
		(fp_line
			(start 0.2794 -0.1143)
			(end -0.2794 -0.1143)
			(stroke
				(width 0.1)
				(type default)
			)
			(layer "B.Fab")
		)
		(fp_line
			(start -0.2794 -0.1143)
			(end -0.2794 0.9144)
			(stroke
				(width 0.1)
				(type default)
			)
			(layer "B.Fab")
		)
		(fp_line
			(start 0.2794 0.9144)
			(end 0.2794 -0.1143)
			(stroke
				(width 0.1)
				(type default)
			)
			(layer "B.Fab")
		)
		(fp_line
			(start -0.2794 0.9144)
			(end 0.2794 0.9144)
			(stroke
				(width 0.1)
				(type default)
			)
			(layer "B.Fab")
		)
		(pad "1" smd custom
			(at 0 0)
			(size 0.10414 0.10414)
			(layers "B.Cu" "B.Mask" "B.Paste")
			(net "P1V05_PCH_STBY")
			(options
				(clearance outline)
				(anchor circle)
			)
			(primitives
				(gr_poly
					(pts
						(xy -0.20828 -0.08636) (xy -0.20828 0.08636) (xy -0.08636 0.20828) (xy 0.086614 0.20828) (xy 0.20828 0.086614)
						(xy 0.20828 -0.08636) (xy 0.08636 -0.20828) (xy -0.08636 -0.20828)
					)
					(width 0)
					(fill yes)
				)
			)
		)
		(pad "2" smd custom
			(at 0 0.8001)
			(size 0.10414 0.10414)
			(layers "B.Cu" "B.Mask" "B.Paste")
			(net "GND")
			(options
				(clearance outline)
				(anchor circle)
			)
			(primitives
				(gr_poly
					(pts
						(xy -0.20828 -0.08636) (xy -0.20828 0.08636) (xy -0.08636 0.20828) (xy 0.086614 0.20828) (xy 0.20828 0.086614)
						(xy 0.20828 -0.08636) (xy 0.08636 -0.20828) (xy -0.08636 -0.20828)
					)
					(width 0)
					(fill yes)
				)
			)
		)
		(zone
			(layer "B.Cu")
			(hatch none 0.5)
			(connect_pads
				(clearance 0)
			)
			(min_thickness 0.25)
			(keepout
				(tracks not_allowed)
				(vias allowed)
				(pads allowed)
				(copperpour not_allowed)
				(footprints allowed)
			)
			(placement
				(enabled no)
				(sheetname "")
			)
			(fill
				(thermal_gap 0.5)
				(thermal_bridge_width 0.5)
				(island_removal_mode 0)
			)
			(polygon
				(pts
					(xy 387.78815 -114.99723) (xy 388.16915 -114.99723) (xy 388.16915 -114.82197) (xy 387.78815 -114.821716)
				)
			)
		)
		(zone
			(layer "B.Cu")
			(hatch none 0.5)
			(connect_pads
				(clearance 0)
			)
			(min_thickness 0.25)
			(keepout
				(tracks allowed)
				(vias not_allowed)
				(pads allowed)
				(copperpour not_allowed)
				(footprints allowed)
			)
			(placement
				(enabled no)
				(sheetname "")
			)
			(fill
				(thermal_gap 0.5)
				(thermal_bridge_width 0.5)
				(island_removal_mode 0)
			)
			(polygon
				(pts
					(xy 387.78815 -114.99723) (xy 388.16915 -114.99723) (xy 388.16915 -114.82197) (xy 387.78815 -114.821716)
				)
			)
		)
	)
	(footprint ""
		(layer "B.Cu")
		(at 281.3812 -76.4794 90)
		(property "Reference" "R4P5"
			(at 0 0 90)
			(layer "B.SilkS")
			(hide yes)
			(effects
				(font
					(size 1.27 1.27)
				)
				(justify mirror)
			)
		)
		(property "Value" ""
			(at 0 0 90)
			(layer "B.Fab")
			(effects
				(font
					(size 1.27 1.27)
				)
				(justify mirror)
			)
		)
		(duplicate_pad_numbers_are_jumpers no)
		(fp_rect
			(start -0.2794 -0.1016)
			(end 0.2794 0.9906)
			(stroke
				(width 0)
				(type default)
			)
			(fill no)
			(layer "B.CrtYd")
		)
		(fp_line
			(start 0.2794 -0.1016)
			(end 0.2794 0.9906)
			(stroke
				(width 0.1)
				(type default)
			)
			(layer "B.Fab")
		)
		(fp_line
			(start -0.2794 -0.1016)
			(end 0.2794 -0.1016)
			(stroke
				(width 0.1)
				(type default)
			)
			(layer "B.Fab")
		)
		(fp_line
			(start 0.2794 0.9906)
			(end -0.2794 0.9906)
			(stroke
				(width 0.1)
				(type default)
			)
			(layer "B.Fab")
		)
		(fp_line
			(start -0.2794 0.9906)
			(end -0.2794 -0.1016)
			(stroke
				(width 0.1)
				(type default)
			)
			(layer "B.Fab")
		)
		(pad "1" smd rect
			(at 0 0 270)
			(size 0.508 0.508)
			(layers "B.Cu" "B.Mask" "B.Paste")
			(net "GND")
		)
		(pad "2" smd rect
			(at 0 0.889 270)
			(size 0.508 0.508)
			(layers "B.Cu" "B.Mask" "B.Paste")
			(net "PD_CPU0_MCP01_DMON")
		)
		(zone
			(layer "B.Cu")
			(hatch none 0.5)
			(connect_pads
				(clearance 0)
			)
			(min_thickness 0.25)
			(keepout
				(tracks allowed)
				(vias not_allowed)
				(pads allowed)
				(copperpour not_allowed)
				(footprints allowed)
			)
			(placement
				(enabled no)
				(sheetname "")
			)
			(fill
				(thermal_gap 0.5)
				(thermal_bridge_width 0.5)
				(island_removal_mode 0)
			)
			(polygon
				(pts
					(xy 281.6352 -76.2254) (xy 282.0162 -76.2254) (xy 282.0162 -76.7334) (xy 281.6352 -76.7334)
				)
			)
		)
		(zone
			(layer "B.Cu")
			(hatch none 0.5)
			(connect_pads
				(clearance 0)
			)
			(min_thickness 0.25)
			(keepout
				(tracks not_allowed)
				(vias allowed)
				(pads allowed)
				(copperpour not_allowed)
				(footprints allowed)
			)
			(placement
				(enabled no)
				(sheetname "")
			)
			(fill
				(thermal_gap 0.5)
				(thermal_bridge_width 0.5)
				(island_removal_mode 0)
			)
			(polygon
				(pts
					(xy 281.6352 -76.2254) (xy 282.0162 -76.2254) (xy 282.0162 -76.7334) (xy 281.6352 -76.7334)
				)
			)
		)
	)
	(footprint ""
		(layer "B.Cu")
		(at 115.353592 -77.366114)
		(property "Reference" "C7P12"
			(at 0 0 0)
			(layer "B.SilkS")
			(hide yes)
			(effects
				(font
					(size 1.27 1.27)
				)
				(justify mirror)
			)
		)
		(property "Value" ""
			(at 0 0 0)
			(layer "B.Fab")
			(effects
				(font
					(size 1.27 1.27)
				)
				(justify mirror)
			)
		)
		(duplicate_pad_numbers_are_jumpers no)
		(fp_poly
			(pts
				(xy 0.4953 -0.2032) (xy -0.4953 -0.2032) (xy -0.4953 1.6002) (xy 0.4953 1.6002)
			)
			(stroke
				(width 0)
				(type default)
			)
			(fill no)
			(layer "B.CrtYd")
		)
		(fp_line
			(start -0.4953 -0.2032)
			(end -0.4953 1.6002)
			(stroke
				(width 0.1)
				(type default)
			)
			(layer "B.Fab")
		)
		(fp_line
			(start -0.4953 1.6002)
			(end 0.4953 1.6002)
			(stroke
				(width 0.1)
				(type default)
			)
			(layer "B.Fab")
		)
		(fp_line
			(start 0.4953 -0.2032)
			(end -0.4953 -0.2032)
			(stroke
				(width 0.1)
				(type default)
			)
			(layer "B.Fab")
		)
		(fp_line
			(start 0.4953 1.6002)
			(end 0.4953 -0.2032)
			(stroke
				(width 0.1)
				(type default)
			)
			(layer "B.Fab")
		)
		(pad "1" smd rect
			(at 0 0 180)
			(size 0.762 0.889)
			(layers "B.Cu" "B.Mask" "B.Paste")
			(net "PVCCIO_CPU1")
		)
		(pad "2" smd rect
			(at 0 1.397 180)
			(size 0.762 0.889)
			(layers "B.Cu" "B.Mask" "B.Paste")
			(net "GND")
		)
		(zone
			(layer "B.Cu")
			(hatch none 0.5)
			(connect_pads
				(clearance 0)
			)
			(min_thickness 0.25)
			(keepout
				(tracks not_allowed)
				(vias allowed)
				(pads allowed)
				(copperpour not_allowed)
				(footprints allowed)
			)
			(placement
				(enabled no)
				(sheetname "")
			)
			(fill
				(thermal_gap 0.5)
				(thermal_bridge_width 0.5)
				(island_removal_mode 0)
			)
			(polygon
				(pts
					(xy 115.734592 -76.921614) (xy 114.972592 -76.921614) (xy 114.972592 -76.413614) (xy 115.734592 -76.413614)
				)
			)
		)
	)
	(footprint ""
		(layer "B.Cu")
		(at 442.0362 -24.2824)
		(property "Reference" "C25W16"
			(at 0.8382 -0.67818 0)
			(unlocked yes)
			(layer "B.SilkS")
			(effects
				(font
					(size 0.4064 0.254)
					(thickness 0.1524)
				)
				(justify left mirror)
			)
		)
		(property "Value" ""
			(at 0 0 0)
			(layer "B.Fab")
			(effects
				(font
					(size 1.27 1.27)
				)
				(justify mirror)
			)
		)
		(duplicate_pad_numbers_are_jumpers no)
		(fp_poly
			(pts
				(xy -0.3048 -0.1016) (xy -0.3048 0.9906) (xy 0.3048 0.9906) (xy 0.3048 -0.1016)
			)
			(stroke
				(width 0)
				(type default)
			)
			(fill no)
			(layer "B.CrtYd")
		)
		(fp_line
			(start -0.3048 -0.1016)
			(end 0.3048 -0.1016)
			(stroke
				(width 0.1)
				(type default)
			)
			(layer "B.Fab")
		)
		(fp_line
			(start -0.3048 0.9906)
			(end -0.3048 -0.1016)
			(stroke
				(width 0.1)
				(type default)
			)
			(layer "B.Fab")
		)
		(fp_line
			(start 0.3048 -0.1016)
			(end 0.3048 0.9906)
			(stroke
				(width 0.1)
				(type default)
			)
			(layer "B.Fab")
		)
		(fp_line
			(start 0.3048 0.9906)
			(end -0.3048 0.9906)
			(stroke
				(width 0.1)
				(type default)
			)
			(layer "B.Fab")
		)
		(pad "1" smd rect
			(at 0 0 180)
			(size 0.508 0.508)
			(layers "B.Cu" "B.Mask" "B.Paste")
			(net "P1V2_AUX_BMC")
		)
		(pad "2" smd rect
			(at 0 0.889 180)
			(size 0.508 0.508)
			(layers "B.Cu" "B.Mask" "B.Paste")
			(net "GND")
		)
		(zone
			(layer "B.Cu")
			(hatch none 0.5)
			(connect_pads
				(clearance 0)
			)
			(min_thickness 0.25)
			(keepout
				(tracks allowed)
				(vias not_allowed)
				(pads allowed)
				(copperpour not_allowed)
				(footprints allowed)
			)
			(placement
				(enabled no)
				(sheetname "")
			)
			(fill
				(thermal_gap 0.5)
				(thermal_bridge_width 0.5)
				(island_removal_mode 0)
			)
			(polygon
				(pts
					(xy 442.2902 -24.0284) (xy 441.7822 -24.0284) (xy 441.7822 -23.6474) (xy 442.2902 -23.6474)
				)
			)
		)
		(zone
			(layer "B.Cu")
			(hatch none 0.5)
			(connect_pads
				(clearance 0)
			)
			(min_thickness 0.25)
			(keepout
				(tracks not_allowed)
				(vias allowed)
				(pads allowed)
				(copperpour not_allowed)
				(footprints allowed)
			)
			(placement
				(enabled no)
				(sheetname "")
			)
			(fill
				(thermal_gap 0.5)
				(thermal_bridge_width 0.5)
				(island_removal_mode 0)
			)
			(polygon
				(pts
					(xy 442.2902 -23.6474) (xy 441.7822 -23.6474) (xy 441.7822 -24.0284) (xy 442.2902 -24.0284)
				)
			)
		)
	)
	(footprint ""
		(layer "B.Cu")
		(at 17.83842 -102.45852 90)
		(property "Reference" "C9N9"
			(at 0 0 90)
			(layer "B.SilkS")
			(hide yes)
			(effects
				(font
					(size 1.27 1.27)
				)
				(justify mirror)
			)
		)
		(property "Value" ""
			(at 0 0 90)
			(layer "B.Fab")
			(effects
				(font
					(size 1.27 1.27)
				)
				(justify mirror)
			)
		)
		(duplicate_pad_numbers_are_jumpers no)
		(fp_poly
			(pts
				(xy -0.3048 -0.1016) (xy -0.3048 0.9906) (xy 0.3048 0.9906) (xy 0.3048 -0.1016)
			)
			(stroke
				(width 0)
				(type default)
			)
			(fill no)
			(layer "B.CrtYd")
		)
		(fp_line
			(start 0.3048 -0.1016)
			(end 0.3048 0.9906)
			(stroke
				(width 0.1)
				(type default)
			)
			(layer "B.Fab")
		)
		(fp_line
			(start -0.3048 -0.1016)
			(end 0.3048 -0.1016)
			(stroke
				(width 0.1)
				(type default)
			)
			(layer "B.Fab")
		)
		(fp_line
			(start 0.3048 0.9906)
			(end -0.3048 0.9906)
			(stroke
				(width 0.1)
				(type default)
			)
			(layer "B.Fab")
		)
		(fp_line
			(start -0.3048 0.9906)
			(end -0.3048 -0.1016)
			(stroke
				(width 0.1)
				(type default)
			)
			(layer "B.Fab")
		)
		(pad "1" smd rect
			(at 0 0 270)
			(size 0.508 0.508)
			(layers "B.Cu" "B.Mask" "B.Paste")
			(net "P3E_CPU1_PE3_MP_C_TXN<15>")
		)
		(pad "2" smd rect
			(at 0 0.889 270)
			(size 0.508 0.508)
			(layers "B.Cu" "B.Mask" "B.Paste")
			(net "P3E_CPU1_PE3_MP_TXN<15>")
		)
		(zone
			(layer "B.Cu")
			(hatch none 0.5)
			(connect_pads
				(clearance 0)
			)
			(min_thickness 0.25)
			(keepout
				(tracks allowed)
				(vias not_allowed)
				(pads allowed)
				(copperpour not_allowed)
				(footprints allowed)
			)
			(placement
				(enabled no)
				(sheetname "")
			)
			(fill
				(thermal_gap 0.5)
				(thermal_bridge_width 0.5)
				(island_removal_mode 0)
			)
			(polygon
				(pts
					(xy 18.09242 -102.71252) (xy 18.09242 -102.20452) (xy 18.47342 -102.20452) (xy 18.47342 -102.71252)
				)
			)
		)
		(zone
			(layer "B.Cu")
			(hatch none 0.5)
			(connect_pads
				(clearance 0)
			)
			(min_thickness 0.25)
			(keepout
				(tracks not_allowed)
				(vias allowed)
				(pads allowed)
				(copperpour not_allowed)
				(footprints allowed)
			)
			(placement
				(enabled no)
				(sheetname "")
			)
			(fill
				(thermal_gap 0.5)
				(thermal_bridge_width 0.5)
				(island_removal_mode 0)
			)
			(polygon
				(pts
					(xy 18.47342 -102.71252) (xy 18.47342 -102.20452) (xy 18.09242 -102.20452) (xy 18.09242 -102.71252)
				)
			)
		)
	)
	(footprint ""
		(layer "B.Cu")
		(at 403.344634 -79.235808 90)
		(property "Reference" "R6W28"
			(at 0.8382 -0.67818 90)
			(unlocked yes)
			(layer "B.SilkS")
			(effects
				(font
					(size 0.4064 0.254)
					(thickness 0.1524)
				)
				(justify left mirror)
			)
		)
		(property "Value" ""
			(at 0 0 90)
			(layer "B.Fab")
			(effects
				(font
					(size 1.27 1.27)
				)
				(justify mirror)
			)
		)
		(duplicate_pad_numbers_are_jumpers no)
		(fp_poly
			(pts
				(xy 0.2794 -0.1016) (xy -0.2794 -0.1016) (xy -0.2794 0.9906) (xy 0.2794 0.9906)
			)
			(stroke
				(width 0)
				(type default)
			)
			(fill no)
			(layer "B.CrtYd")
		)
		(fp_line
			(start 0.2794 -0.1016)
			(end 0.2794 0.9906)
			(stroke
				(width 0.1)
				(type default)
			)
			(layer "B.Fab")
		)
		(fp_line
			(start -0.2794 -0.1016)
			(end 0.2794 -0.1016)
			(stroke
				(width 0.1)
				(type default)
			)
			(layer "B.Fab")
		)
		(fp_line
			(start 0.2794 0.9906)
			(end -0.2794 0.9906)
			(stroke
				(width 0.1)
				(type default)
			)
			(layer "B.Fab")
		)
		(fp_line
			(start -0.2794 0.9906)
			(end -0.2794 -0.1016)
			(stroke
				(width 0.1)
				(type default)
			)
			(layer "B.Fab")
		)
		(pad "1" smd rect
			(at 0 0 270)
			(size 0.508 0.508)
			(layers "B.Cu" "B.Mask" "B.Paste")
			(net "P3V3_STBY")
		)
		(pad "2" smd rect
			(at 0 0.889 270)
			(size 0.508 0.508)
			(layers "B.Cu" "B.Mask" "B.Paste")
			(net "HSC_SMBUS_SWITCH_EN")
		)
		(zone
			(layer "B.Cu")
			(hatch none 0.5)
			(connect_pads
				(clearance 0)
			)
			(min_thickness 0.25)
			(keepout
				(tracks allowed)
				(vias not_allowed)
				(pads allowed)
				(copperpour not_allowed)
				(footprints allowed)
			)
			(placement
				(enabled no)
				(sheetname "")
			)
			(fill
				(thermal_gap 0.5)
				(thermal_bridge_width 0.5)
				(island_removal_mode 0)
			)
			(polygon
				(pts
					(xy 403.598634 -79.489808) (xy 403.598634 -78.981808) (xy 403.979634 -78.981808) (xy 403.979634 -79.489808)
				)
			)
		)
		(zone
			(layer "B.Cu")
			(hatch none 0.5)
			(connect_pads
				(clearance 0)
			)
			(min_thickness 0.25)
			(keepout
				(tracks not_allowed)
				(vias allowed)
				(pads allowed)
				(copperpour not_allowed)
				(footprints allowed)
			)
			(placement
				(enabled no)
				(sheetname "")
			)
			(fill
				(thermal_gap 0.5)
				(thermal_bridge_width 0.5)
				(island_removal_mode 0)
			)
			(polygon
				(pts
					(xy 403.979634 -79.489808) (xy 403.979634 -78.981808) (xy 403.598634 -78.981808) (xy 403.598634 -79.489808)
				)
			)
		)
	)
	(footprint ""
		(layer "B.Cu")
		(at 347.5736 -7.1628 -90)
		(property "Reference" "C3U2"
			(at 0 0 90)
			(layer "B.SilkS")
			(hide yes)
			(effects
				(font
					(size 1.27 1.27)
				)
				(justify mirror)
			)
		)
		(property "Value" ""
			(at 0 0 90)
			(layer "B.Fab")
			(effects
				(font
					(size 1.27 1.27)
				)
				(justify mirror)
			)
		)
		(duplicate_pad_numbers_are_jumpers no)
		(fp_rect
			(start 0.7239 1.9939)
			(end -0.7239 -0.2159)
			(stroke
				(width 0)
				(type default)
			)
			(fill no)
			(layer "B.CrtYd")
		)
		(fp_line
			(start -0.7239 1.9939)
			(end -0.7239 -0.2159)
			(stroke
				(width 0.1)
				(type default)
			)
			(layer "B.Fab")
		)
		(fp_line
			(start 0.7239 1.9939)
			(end -0.7239 1.9939)
			(stroke
				(width 0.1)
				(type default)
			)
			(layer "B.Fab")
		)
		(fp_line
			(start -0.7239 -0.2159)
			(end 0.7239 -0.2159)
			(stroke
				(width 0.1)
				(type default)
			)
			(layer "B.Fab")
		)
		(fp_line
			(start 0.7239 -0.2159)
			(end 0.7239 1.9939)
			(stroke
				(width 0.1)
				(type default)
			)
			(layer "B.Fab")
		)
		(pad "1" smd rect
			(at 0 0 90)
			(size 1.27 1.016)
			(layers "B.Cu" "B.Mask" "B.Paste")
			(net "VR_FET_SW_P12V_STBY_PVDDQ_ABC")
		)
		(pad "2" smd rect
			(at 0 1.778 90)
			(size 1.27 1.016)
			(layers "B.Cu" "B.Mask" "B.Paste")
			(net "GND")
		)
		(zone
			(layer "B.Cu")
			(hatch none 0.5)
			(connect_pads
				(clearance 0)
			)
			(min_thickness 0.25)
			(keepout
				(tracks not_allowed)
				(vias allowed)
				(pads allowed)
				(copperpour not_allowed)
				(footprints allowed)
			)
			(placement
				(enabled no)
				(sheetname "")
			)
			(fill
				(thermal_gap 0.5)
				(thermal_bridge_width 0.5)
				(island_removal_mode 0)
			)
			(polygon
				(pts
					(xy 346.3036 -6.5278) (xy 347.0656 -6.5278) (xy 347.0656 -7.7978) (xy 346.3036 -7.7978)
				)
			)
		)
	)
)
